(kicad_pcb
	(version 20260206)
	(generator "pcbnew")
	(generator_version "10.0")
	(general
		(thickness 1.6)
		(legacy_teardrops no)
	)
	(paper "A4")
	(title_block
		(title "01162023_DA0F0TEBIF0_F0T_Expander_BD_F_brd_V02_OCP.brd")
		(comment 1 "Grand Teton / footprints 5533-5540 of 9728")
	)
	(layers
		(0 "F.Cu" signal "TOP")
		(4 "In1.Cu" signal "GND")
		(6 "In2.Cu" signal "VCC")
		(8 "In3.Cu" signal "VCC1")
		(10 "In4.Cu" signal "GND1")
		(12 "In5.Cu" signal "IN1")
		(14 "In6.Cu" signal "GND2")
		(16 "In7.Cu" signal "IN2")
		(18 "In8.Cu" signal "GND3")
		(20 "In9.Cu" signal "IN3")
		(22 "In10.Cu" signal "GND4")
		(24 "In11.Cu" signal "IN4")
		(26 "In12.Cu" signal "GND5")
		(28 "In13.Cu" signal "IN5")
		(30 "In14.Cu" signal "GND6")
		(32 "In15.Cu" signal "IN6")
		(34 "In16.Cu" signal "GND7")
		(2 "B.Cu" signal "BOTTOM")
		(9 "F.Adhes" user "F.Adhesive")
		(11 "B.Adhes" user "B.Adhesive")
		(13 "F.Paste" user "Package Geometry/Pastemask Top")
		(15 "B.Paste" user "Package Geometry/Pastemask Bottom")
		(5 "F.SilkS" user "Ref Des/Silkscreen Top")
		(7 "B.SilkS" user "Ref Des/Silkscreen Bottom")
		(1 "F.Mask" user "Board Geometry/Soldermask Top")
		(3 "B.Mask" user "Board Geometry/Soldermask Bottom")
		(17 "Dwgs.User" user "User.Drawings")
		(19 "Cmts.User" user "User.Comments")
		(21 "Eco1.User" user "User.Eco1")
		(23 "Eco2.User" user "User.Eco2")
		(25 "Edge.Cuts" user "Board Geometry/Outline")
		(27 "Margin" user)
		(31 "F.CrtYd" user "Package Geometry/Place Bound Top")
		(29 "B.CrtYd" user "Package Geometry/Place Bound Bottom")
		(35 "F.Fab" user "Ref Des/Assembly Top")
		(33 "B.Fab" user "Ref Des/Assembly Bottom")
	)
	(footprint ""
		(layer "F.Cu")
		(at 453.151494 -99.177602 -90)
		(property "Reference" "PD13"
			(at 4.232402 -2.779776 90)
			(unlocked yes)
			(layer "F.SilkS")
			(effects
				(font
					(size 0.7874 0.5842)
					(thickness 0.1524)
				)
				(justify left)
			)
		)
		(property "Value" ""
			(at 0 0 270)
			(layer "F.Fab")
			(effects
				(font
					(size 1.27 1.27)
				)
			)
		)
		(duplicate_pad_numbers_are_jumpers no)
		(fp_line
			(start -3.656584 1.970024)
			(end 4.240784 1.970024)
			(stroke
				(width 0.1524)
				(type default)
			)
			(layer "F.SilkS")
		)
		(fp_line
			(start 4.240784 1.970024)
			(end 4.240784 -1.970024)
			(stroke
				(width 0.1524)
				(type default)
			)
			(layer "F.SilkS")
		)
		(fp_line
			(start -3.656584 -1.970024)
			(end -3.656584 1.970024)
			(stroke
				(width 0.1524)
				(type default)
			)
			(layer "F.SilkS")
		)
		(fp_line
			(start 4.240784 -1.970024)
			(end -3.656584 -1.970024)
			(stroke
				(width 0.1524)
				(type default)
			)
			(layer "F.SilkS")
		)
		(fp_rect
			(start 4.240784 1.970024)
			(end 3.580384 -1.970024)
			(stroke
				(width 0)
				(type default)
			)
			(fill yes)
			(layer "F.SilkS")
		)
		(fp_line
			(start -2.3749 1.970024)
			(end 2.3749 1.970024)
			(stroke
				(width 0.1)
				(type default)
			)
			(layer "F.Fab")
		)
		(fp_line
			(start 2.3749 1.970024)
			(end 2.3749 -1.970024)
			(stroke
				(width 0.1)
				(type default)
			)
			(layer "F.Fab")
		)
		(fp_line
			(start -2.3749 -1.970024)
			(end -2.3749 1.970024)
			(stroke
				(width 0.1)
				(type default)
			)
			(layer "F.Fab")
		)
		(fp_line
			(start 2.3749 -1.970024)
			(end -2.3749 -1.970024)
			(stroke
				(width 0.1)
				(type default)
			)
			(layer "F.Fab")
		)
		(fp_text user "+"
			(at -4.9784 -0.23495 270)
			(unlocked yes)
			(layer "F.Fab")
			(effects
				(font
					(size 1.905 1.4224)
					(thickness 0.1524)
				)
				(justify left)
			)
		)
		(fp_text user "-"
			(at 4.1656 -0.23495 270)
			(unlocked yes)
			(layer "F.Fab")
			(effects
				(font
					(size 1.905 1.4224)
					(thickness 0.1524)
				)
				(justify left)
			)
		)
		(pad "A" smd rect
			(at -2.450084 0 270)
			(size 2.159 2.2606)
			(layers "F.Cu" "F.Mask" "F.Paste")
			(net "GND")
		)
		(pad "C" smd rect
			(at 2.450084 0 270)
			(size 2.159 2.2606)
			(layers "F.Cu" "F.Mask" "F.Paste")
			(net "P12V_AUX")
		)
	)
	(footprint ""
		(layer "F.Cu")
		(at 299.875702 -343.952322 90)
		(property "Reference" "C2370"
			(at 0 0 90)
			(layer "F.SilkS")
			(hide yes)
			(effects
				(font
					(size 1.27 1.27)
				)
			)
		)
		(property "Value" ""
			(at 0 0 90)
			(layer "F.Fab")
			(effects
				(font
					(size 1.27 1.27)
				)
			)
		)
		(duplicate_pad_numbers_are_jumpers no)
		(fp_line
			(start 0.299974 -0.150114)
			(end 0.299974 0.150114)
			(stroke
				(width 0.1)
				(type default)
			)
			(layer "F.Fab")
		)
		(fp_line
			(start -0.299974 -0.150114)
			(end 0.299974 -0.150114)
			(stroke
				(width 0.1)
				(type default)
			)
			(layer "F.Fab")
		)
		(fp_line
			(start 0.299974 0.150114)
			(end -0.299974 0.150114)
			(stroke
				(width 0.1)
				(type default)
			)
			(layer "F.Fab")
		)
		(fp_line
			(start -0.299974 0.150114)
			(end -0.299974 -0.150114)
			(stroke
				(width 0.1)
				(type default)
			)
			(layer "F.Fab")
		)
		(pad "1" smd rect
			(at -0.2667 0 90)
			(size 0.3048 0.381)
			(layers "F.Cu" "F.Mask" "F.Paste")
			(net "P5E_PEX2_STN4_TX_DN<65>")
		)
		(pad "2" smd rect
			(at 0.2667 0 90)
			(size 0.3048 0.381)
			(layers "F.Cu" "F.Mask" "F.Paste")
			(net "P5E_PEX2_STN4_TX_C_DN<65>")
		)
	)
	(footprint ""
		(layer "F.Cu")
		(at 86.178898 -59.577986 -90)
		(property "Reference" "R893"
			(at 0 0 270)
			(layer "F.SilkS")
			(hide yes)
			(effects
				(font
					(size 1.27 1.27)
				)
			)
		)
		(property "Value" ""
			(at 0 0 270)
			(layer "F.Fab")
			(effects
				(font
					(size 1.27 1.27)
				)
			)
		)
		(duplicate_pad_numbers_are_jumpers no)
		(fp_line
			(start -0.7874 0.4064)
			(end -0.7874 -0.4064)
			(stroke
				(width 0.1524)
				(type default)
			)
			(layer "F.SilkS")
		)
		(fp_line
			(start 0.7874 0.4064)
			(end -0.7874 0.4064)
			(stroke
				(width 0.1524)
				(type default)
			)
			(layer "F.SilkS")
		)
		(fp_line
			(start -0.7874 -0.4064)
			(end 0.7874 -0.4064)
			(stroke
				(width 0.1524)
				(type default)
			)
			(layer "F.SilkS")
		)
		(fp_line
			(start 0.7874 -0.4064)
			(end 0.7874 0.4064)
			(stroke
				(width 0.1524)
				(type default)
			)
			(layer "F.SilkS")
		)
		(fp_line
			(start -0.67945 0.3048)
			(end -0.67945 -0.305054)
			(stroke
				(width 0.1)
				(type default)
			)
			(layer "F.Fab")
		)
		(fp_line
			(start -0.12065 0.3048)
			(end -0.67945 0.3048)
			(stroke
				(width 0.1)
				(type default)
			)
			(layer "F.Fab")
		)
		(fp_line
			(start 0.120396 0.3048)
			(end 0.120396 0.2794)
			(stroke
				(width 0.1)
				(type default)
			)
			(layer "F.Fab")
		)
		(fp_line
			(start 0.67945 0.3048)
			(end 0.120396 0.3048)
			(stroke
				(width 0.1)
				(type default)
			)
			(layer "F.Fab")
		)
		(fp_line
			(start -0.12065 0.2794)
			(end -0.12065 0.3048)
			(stroke
				(width 0.1)
				(type default)
			)
			(layer "F.Fab")
		)
		(fp_line
			(start 0.120396 0.2794)
			(end -0.12065 0.2794)
			(stroke
				(width 0.1)
				(type default)
			)
			(layer "F.Fab")
		)
		(fp_line
			(start -0.12065 -0.2794)
			(end 0.12065 -0.2794)
			(stroke
				(width 0.1)
				(type default)
			)
			(layer "F.Fab")
		)
		(fp_line
			(start 0.12065 -0.2794)
			(end 0.12065 -0.3048)
			(stroke
				(width 0.1)
				(type default)
			)
			(layer "F.Fab")
		)
		(fp_line
			(start 0.12065 -0.3048)
			(end 0.67945 -0.3048)
			(stroke
				(width 0.1)
				(type default)
			)
			(layer "F.Fab")
		)
		(fp_line
			(start 0.67945 -0.3048)
			(end 0.67945 0.3048)
			(stroke
				(width 0.1)
				(type default)
			)
			(layer "F.Fab")
		)
		(fp_line
			(start -0.67945 -0.305054)
			(end -0.12065 -0.305054)
			(stroke
				(width 0.1)
				(type default)
			)
			(layer "F.Fab")
		)
		(fp_line
			(start -0.12065 -0.305054)
			(end -0.12065 -0.2794)
			(stroke
				(width 0.1)
				(type default)
			)
			(layer "F.Fab")
		)
		(pad "1" smd circle
			(at -0.40005 0 270)
			(size 0 0)
			(layers "F.Cu" "F.Mask" "F.Paste")
			(net "P3V3_SSD3")
		)
		(pad "2" smd circle
			(at 0.40005 0 270)
			(size 0 0)
			(layers "F.Cu" "F.Mask" "F.Paste")
			(net "PWRGD_P3V3_SSD3")
		)
	)
	(footprint ""
		(layer "F.Cu")
		(at 417.158424 -241.83975 180)
		(property "Reference" "R6620"
			(at 0 0 180)
			(layer "F.SilkS")
			(hide yes)
			(effects
				(font
					(size 1.27 1.27)
				)
			)
		)
		(property "Value" ""
			(at 0 0 180)
			(layer "F.Fab")
			(effects
				(font
					(size 1.27 1.27)
				)
			)
		)
		(duplicate_pad_numbers_are_jumpers no)
		(fp_line
			(start 0.7874 0.4064)
			(end -0.7874 0.4064)
			(stroke
				(width 0.1524)
				(type default)
			)
			(layer "F.SilkS")
		)
		(fp_line
			(start 0.7874 -0.4064)
			(end 0.7874 0.4064)
			(stroke
				(width 0.1524)
				(type default)
			)
			(layer "F.SilkS")
		)
		(fp_line
			(start -0.7874 0.4064)
			(end -0.7874 -0.4064)
			(stroke
				(width 0.1524)
				(type default)
			)
			(layer "F.SilkS")
		)
		(fp_line
			(start -0.7874 -0.4064)
			(end 0.7874 -0.4064)
			(stroke
				(width 0.1524)
				(type default)
			)
			(layer "F.SilkS")
		)
		(fp_line
			(start 0.67945 0.3048)
			(end 0.120396 0.3048)
			(stroke
				(width 0.1)
				(type default)
			)
			(layer "F.Fab")
		)
		(fp_line
			(start 0.67945 -0.3048)
			(end 0.67945 0.3048)
			(stroke
				(width 0.1)
				(type default)
			)
			(layer "F.Fab")
		)
		(fp_line
			(start 0.12065 -0.2794)
			(end 0.12065 -0.3048)
			(stroke
				(width 0.1)
				(type default)
			)
			(layer "F.Fab")
		)
		(fp_line
			(start 0.12065 -0.3048)
			(end 0.67945 -0.3048)
			(stroke
				(width 0.1)
				(type default)
			)
			(layer "F.Fab")
		)
		(fp_line
			(start 0.120396 0.3048)
			(end 0.120396 0.2794)
			(stroke
				(width 0.1)
				(type default)
			)
			(layer "F.Fab")
		)
		(fp_line
			(start 0.120396 0.2794)
			(end -0.12065 0.2794)
			(stroke
				(width 0.1)
				(type default)
			)
			(layer "F.Fab")
		)
		(fp_line
			(start -0.12065 0.3048)
			(end -0.67945 0.3048)
			(stroke
				(width 0.1)
				(type default)
			)
			(layer "F.Fab")
		)
		(fp_line
			(start -0.12065 0.2794)
			(end -0.12065 0.3048)
			(stroke
				(width 0.1)
				(type default)
			)
			(layer "F.Fab")
		)
		(fp_line
			(start -0.12065 -0.2794)
			(end 0.12065 -0.2794)
			(stroke
				(width 0.1)
				(type default)
			)
			(layer "F.Fab")
		)
		(fp_line
			(start -0.12065 -0.305054)
			(end -0.12065 -0.2794)
			(stroke
				(width 0.1)
				(type default)
			)
			(layer "F.Fab")
		)
		(fp_line
			(start -0.67945 0.3048)
			(end -0.67945 -0.305054)
			(stroke
				(width 0.1)
				(type default)
			)
			(layer "F.Fab")
		)
		(fp_line
			(start -0.67945 -0.305054)
			(end -0.12065 -0.305054)
			(stroke
				(width 0.1)
				(type default)
			)
			(layer "F.Fab")
		)
		(pad "1" smd circle
			(at -0.40005 0 180)
			(size 0 0)
			(layers "F.Cu" "F.Mask" "F.Paste")
			(net "UART_PEX2_SDB_BUF_R_TX")
		)
		(pad "2" smd circle
			(at 0.40005 0 180)
			(size 0 0)
			(layers "F.Cu" "F.Mask" "F.Paste")
			(net "UART_PEX2_SDB_BUF_R1_TX")
		)
	)
	(footprint ""
		(layer "F.Cu")
		(at 112.311942 -112.547654)
		(property "Reference" "PC617"
			(at 0 0 0)
			(layer "F.SilkS")
			(hide yes)
			(effects
				(font
					(size 1.27 1.27)
				)
			)
		)
		(property "Value" ""
			(at 0 0 0)
			(layer "F.Fab")
			(effects
				(font
					(size 1.27 1.27)
				)
			)
		)
		(duplicate_pad_numbers_are_jumpers no)
		(fp_line
			(start -0.7874 -0.4064)
			(end 0.7874 -0.4064)
			(stroke
				(width 0.1524)
				(type default)
			)
			(layer "F.SilkS")
		)
		(fp_line
			(start -0.7874 0.4064)
			(end -0.7874 -0.4064)
			(stroke
				(width 0.1524)
				(type default)
			)
			(layer "F.SilkS")
		)
		(fp_line
			(start 0.7874 -0.4064)
			(end 0.7874 0.4064)
			(stroke
				(width 0.1524)
				(type default)
			)
			(layer "F.SilkS")
		)
		(fp_line
			(start 0.7874 0.4064)
			(end -0.7874 0.4064)
			(stroke
				(width 0.1524)
				(type default)
			)
			(layer "F.SilkS")
		)
		(fp_line
			(start -0.67945 -0.305054)
			(end -0.12065 -0.305054)
			(stroke
				(width 0.1)
				(type default)
			)
			(layer "F.Fab")
		)
		(fp_line
			(start -0.67945 0.3048)
			(end -0.67945 -0.305054)
			(stroke
				(width 0.1)
				(type default)
			)
			(layer "F.Fab")
		)
		(fp_line
			(start -0.12065 -0.305054)
			(end -0.12065 -0.2794)
			(stroke
				(width 0.1)
				(type default)
			)
			(layer "F.Fab")
		)
		(fp_line
			(start -0.12065 -0.2794)
			(end 0.12065 -0.2794)
			(stroke
				(width 0.1)
				(type default)
			)
			(layer "F.Fab")
		)
		(fp_line
			(start -0.12065 0.2794)
			(end -0.12065 0.3048)
			(stroke
				(width 0.1)
				(type default)
			)
			(layer "F.Fab")
		)
		(fp_line
			(start -0.12065 0.3048)
			(end -0.67945 0.3048)
			(stroke
				(width 0.1)
				(type default)
			)
			(layer "F.Fab")
		)
		(fp_line
			(start 0.120396 0.2794)
			(end -0.12065 0.2794)
			(stroke
				(width 0.1)
				(type default)
			)
			(layer "F.Fab")
		)
		(fp_line
			(start 0.120396 0.3048)
			(end 0.120396 0.2794)
			(stroke
				(width 0.1)
				(type default)
			)
			(layer "F.Fab")
		)
		(fp_line
			(start 0.12065 -0.3048)
			(end 0.67945 -0.3048)
			(stroke
				(width 0.1)
				(type default)
			)
			(layer "F.Fab")
		)
		(fp_line
			(start 0.12065 -0.2794)
			(end 0.12065 -0.3048)
			(stroke
				(width 0.1)
				(type default)
			)
			(layer "F.Fab")
		)
		(fp_line
			(start 0.67945 -0.3048)
			(end 0.67945 0.3048)
			(stroke
				(width 0.1)
				(type default)
			)
			(layer "F.Fab")
		)
		(fp_line
			(start 0.67945 0.3048)
			(end 0.120396 0.3048)
			(stroke
				(width 0.1)
				(type default)
			)
			(layer "F.Fab")
		)
		(pad "1" smd circle
			(at -0.40005 0)
			(size 0 0)
			(layers "F.Cu" "F.Mask" "F.Paste")
			(net "P12V_NIC1_CO_ISET_R")
		)
		(pad "2" smd circle
			(at 0.40005 0)
			(size 0 0)
			(layers "F.Cu" "F.Mask" "F.Paste")
			(net "GND")
		)
	)
	(footprint ""
		(layer "F.Cu")
		(at 424.683428 -49.94148)
		(property "Reference" "R665"
			(at 0 0 0)
			(layer "F.SilkS")
			(hide yes)
			(effects
				(font
					(size 1.27 1.27)
				)
			)
		)
		(property "Value" ""
			(at 0 0 0)
			(layer "F.Fab")
			(effects
				(font
					(size 1.27 1.27)
				)
			)
		)
		(duplicate_pad_numbers_are_jumpers no)
		(fp_line
			(start -0.7874 -0.4064)
			(end 0.7874 -0.4064)
			(stroke
				(width 0.1524)
				(type default)
			)
			(layer "F.SilkS")
		)
		(fp_line
			(start -0.7874 0.4064)
			(end -0.7874 -0.4064)
			(stroke
				(width 0.1524)
				(type default)
			)
			(layer "F.SilkS")
		)
		(fp_line
			(start 0.7874 -0.4064)
			(end 0.7874 0.4064)
			(stroke
				(width 0.1524)
				(type default)
			)
			(layer "F.SilkS")
		)
		(fp_line
			(start 0.7874 0.4064)
			(end -0.7874 0.4064)
			(stroke
				(width 0.1524)
				(type default)
			)
			(layer "F.SilkS")
		)
		(fp_line
			(start -0.67945 -0.305054)
			(end -0.12065 -0.305054)
			(stroke
				(width 0.1)
				(type default)
			)
			(layer "F.Fab")
		)
		(fp_line
			(start -0.67945 0.3048)
			(end -0.67945 -0.305054)
			(stroke
				(width 0.1)
				(type default)
			)
			(layer "F.Fab")
		)
		(fp_line
			(start -0.12065 -0.305054)
			(end -0.12065 -0.2794)
			(stroke
				(width 0.1)
				(type default)
			)
			(layer "F.Fab")
		)
		(fp_line
			(start -0.12065 -0.2794)
			(end 0.12065 -0.2794)
			(stroke
				(width 0.1)
				(type default)
			)
			(layer "F.Fab")
		)
		(fp_line
			(start -0.12065 0.2794)
			(end -0.12065 0.3048)
			(stroke
				(width 0.1)
				(type default)
			)
			(layer "F.Fab")
		)
		(fp_line
			(start -0.12065 0.3048)
			(end -0.67945 0.3048)
			(stroke
				(width 0.1)
				(type default)
			)
			(layer "F.Fab")
		)
		(fp_line
			(start 0.120396 0.2794)
			(end -0.12065 0.2794)
			(stroke
				(width 0.1)
				(type default)
			)
			(layer "F.Fab")
		)
		(fp_line
			(start 0.120396 0.3048)
			(end 0.120396 0.2794)
			(stroke
				(width 0.1)
				(type default)
			)
			(layer "F.Fab")
		)
		(fp_line
			(start 0.12065 -0.3048)
			(end 0.67945 -0.3048)
			(stroke
				(width 0.1)
				(type default)
			)
			(layer "F.Fab")
		)
		(fp_line
			(start 0.12065 -0.2794)
			(end 0.12065 -0.3048)
			(stroke
				(width 0.1)
				(type default)
			)
			(layer "F.Fab")
		)
		(fp_line
			(start 0.67945 -0.3048)
			(end 0.67945 0.3048)
			(stroke
				(width 0.1)
				(type default)
			)
			(layer "F.Fab")
		)
		(fp_line
			(start 0.67945 0.3048)
			(end 0.120396 0.3048)
			(stroke
				(width 0.1)
				(type default)
			)
			(layer "F.Fab")
		)
		(pad "1" smd circle
			(at -0.40005 0)
			(size 0 0)
			(layers "F.Cu" "F.Mask" "F.Paste")
			(net "SMB_BIC_I2C6_MUX_SSD_8_15_ADC_R_SCL")
		)
		(pad "2" smd circle
			(at 0.40005 0)
			(size 0 0)
			(layers "F.Cu" "F.Mask" "F.Paste")
			(net "SMB_SSD14_ADC_SCL")
		)
	)
	(footprint ""
		(layer "F.Cu")
		(at 110.01502 -17.999964)
		(property "Reference" "H51"
			(at -4.94157 -5.132578 0)
			(unlocked yes)
			(layer "F.SilkS")
			(effects
				(font
					(size 0.7874 0.5842)
					(thickness 0.1524)
				)
				(justify left)
			)
		)
		(property "Value" ""
			(at 0 0 0)
			(layer "F.Fab")
			(effects
				(font
					(size 1.27 1.27)
				)
			)
		)
		(duplicate_pad_numbers_are_jumpers no)
		(pad "1" thru_hole circle
			(at 0 0)
			(size 10.0076 10.0076)
			(drill 5.6134)
			(layers "*.Cu" "*.Mask")
			(remove_unused_layers no)
			(net "GND")
			(clearance -1.9431)
		)
	)
	(footprint ""
		(layer "F.Cu")
		(at 236.832648 -172.55998 -90)
		(property "Reference" "C2808"
			(at 0 0 270)
			(layer "F.SilkS")
			(hide yes)
			(effects
				(font
					(size 1.27 1.27)
				)
			)
		)
		(property "Value" ""
			(at 0 0 270)
			(layer "F.Fab")
			(effects
				(font
					(size 1.27 1.27)
				)
			)
		)
		(duplicate_pad_numbers_are_jumpers no)
		(fp_line
			(start -0.7874 0.4064)
			(end -0.7874 -0.4064)
			(stroke
				(width 0.1524)
				(type default)
			)
			(layer "F.SilkS")
		)
		(fp_line
			(start 0.7874 0.4064)
			(end -0.7874 0.4064)
			(stroke
				(width 0.1524)
				(type default)
			)
			(layer "F.SilkS")
		)
		(fp_line
			(start -0.7874 -0.4064)
			(end 0.7874 -0.4064)
			(stroke
				(width 0.1524)
				(type default)
			)
			(layer "F.SilkS")
		)
		(fp_line
			(start 0.7874 -0.4064)
			(end 0.7874 0.4064)
			(stroke
				(width 0.1524)
				(type default)
			)
			(layer "F.SilkS")
		)
		(fp_line
			(start -0.67945 0.3048)
			(end -0.67945 -0.305054)
			(stroke
				(width 0.1)
				(type default)
			)
			(layer "F.Fab")
		)
		(fp_line
			(start -0.12065 0.3048)
			(end -0.67945 0.3048)
			(stroke
				(width 0.1)
				(type default)
			)
			(layer "F.Fab")
		)
		(fp_line
			(start 0.120396 0.3048)
			(end 0.120396 0.2794)
			(stroke
				(width 0.1)
				(type default)
			)
			(layer "F.Fab")
		)
		(fp_line
			(start 0.67945 0.3048)
			(end 0.120396 0.3048)
			(stroke
				(width 0.1)
				(type default)
			)
			(layer "F.Fab")
		)
		(fp_line
			(start -0.12065 0.2794)
			(end -0.12065 0.3048)
			(stroke
				(width 0.1)
				(type default)
			)
			(layer "F.Fab")
		)
		(fp_line
			(start 0.120396 0.2794)
			(end -0.12065 0.2794)
			(stroke
				(width 0.1)
				(type default)
			)
			(layer "F.Fab")
		)
		(fp_line
			(start -0.12065 -0.2794)
			(end 0.12065 -0.2794)
			(stroke
				(width 0.1)
				(type default)
			)
			(layer "F.Fab")
		)
		(fp_line
			(start 0.12065 -0.2794)
			(end 0.12065 -0.3048)
			(stroke
				(width 0.1)
				(type default)
			)
			(layer "F.Fab")
		)
		(fp_line
			(start 0.12065 -0.3048)
			(end 0.67945 -0.3048)
			(stroke
				(width 0.1)
				(type default)
			)
			(layer "F.Fab")
		)
		(fp_line
			(start 0.67945 -0.3048)
			(end 0.67945 0.3048)
			(stroke
				(width 0.1)
				(type default)
			)
			(layer "F.Fab")
		)
		(fp_line
			(start -0.67945 -0.305054)
			(end -0.12065 -0.305054)
			(stroke
				(width 0.1)
				(type default)
			)
			(layer "F.Fab")
		)
		(fp_line
			(start -0.12065 -0.305054)
			(end -0.12065 -0.2794)
			(stroke
				(width 0.1)
				(type default)
			)
			(layer "F.Fab")
		)
		(pad "1" smd circle
			(at -0.40005 0 270)
			(size 0 0)
			(layers "F.Cu" "F.Mask" "F.Paste")
			(net "P3V3_AUX")
		)
		(pad "2" smd circle
			(at 0.40005 0 270)
			(size 0 0)
			(layers "F.Cu" "F.Mask" "F.Paste")
			(net "GND")
		)
	)
)
